# SCM (Grand Teton) — schematic netlist excerpt (pin names and nets, part order shuffled) for the footprints in the layout excerpt that follows; sources: Cadence DE-HDL packaged netlist, KiCad conversion of 12092022_DA0F0TMDCD0_F0T_Management_Board_D_brd_V3_OCP.brd

R680  Q_RES  33.2 1% EMPTY  pkg 0402LF  page 13 : A = SPI_BMC_MISO_IO1_R ; B = QSPI_2_PLD_IO1
R51  Q_RES  0 5% CHIP  pkg 0402LF  page 35 : A = H_CPU0_PROCHOT_LVC1_N ; B = H_CPU0_PROCHOT_LVC1_R_N

(kicad_pcb
	(version 20260206)
	(generator "pcbnew")
	(generator_version "10.0")
	(general
		(thickness 1.6)
		(legacy_teardrops no)
	)
	(paper "A4")
	(title_block
		(title "12092022_DA0F0TMDCD0_F0T_Management_Board_D_brd_V3_OCP.brd")
		(comment 1 "Grand Teton / footprints 1203-1204 of 1440")
	)
	(layers
		(0 "F.Cu" signal "TOP")
		(4 "In1.Cu" signal "GND")
		(6 "In2.Cu" signal "IN1")
		(8 "In3.Cu" signal "GND1")
		(10 "In4.Cu" signal "IN2")
		(12 "In5.Cu" signal "VCC")
		(14 "In6.Cu" signal "VCC1")
		(16 "In7.Cu" signal "IN3")
		(18 "In8.Cu" signal "GND2")
		(20 "In9.Cu" signal "IN4")
		(22 "In10.Cu" signal "GND3")
		(2 "B.Cu" signal "BOTTOM")
		(9 "F.Adhes" user "F.Adhesive")
		(11 "B.Adhes" user "B.Adhesive")
		(13 "F.Paste" user "Package Geometry/Pastemask Top")
		(15 "B.Paste" user "Package Geometry/Pastemask Bottom")
		(5 "F.SilkS" user "Ref Des/Silkscreen Top")
		(7 "B.SilkS" user "Ref Des/Silkscreen Bottom")
		(1 "F.Mask" user "Board Geometry/Soldermask Top")
		(3 "B.Mask" user "Board Geometry/Soldermask Bottom")
		(17 "Dwgs.User" user "User.Drawings")
		(19 "Cmts.User" user "User.Comments")
		(21 "Eco1.User" user "User.Eco1")
		(23 "Eco2.User" user "User.Eco2")
		(25 "Edge.Cuts" user "Board Geometry/Outline")
		(27 "Margin" user)
		(31 "F.CrtYd" user "Package Geometry/Place Bound Top")
		(29 "B.CrtYd" user "Package Geometry/Place Bound Bottom")
		(35 "F.Fab" user "Ref Des/Assembly Top")
		(33 "B.Fab" user "Ref Des/Assembly Bottom")
	)
	(footprint ""
		(layer "B.Cu")
		(at 55.1688 -61.0108 90)
		(property "Reference" "R680"
			(at 0 0 90)
			(layer "B.SilkS")
			(hide yes)
			(effects
				(font
					(size 1.27 1.27)
				)
				(justify mirror)
			)
		)
		(property "Value" ""
			(at 0 0 90)
			(layer "B.Fab")
			(effects
				(font
					(size 1.27 1.27)
				)
				(justify mirror)
			)
		)
		(duplicate_pad_numbers_are_jumpers no)
		(fp_line
			(start 0.7874 -0.4064)
			(end -0.7874 -0.4064)
			(stroke
				(width 0.1524)
				(type default)
			)
			(layer "B.SilkS")
		)
		(fp_line
			(start -0.7874 -0.4064)
			(end -0.7874 0.4064)
			(stroke
				(width 0.1524)
				(type default)
			)
			(layer "B.SilkS")
		)
		(fp_line
			(start 0.7874 0.4064)
			(end 0.7874 -0.4064)
			(stroke
				(width 0.1524)
				(type default)
			)
			(layer "B.SilkS")
		)
		(fp_line
			(start -0.7874 0.4064)
			(end 0.7874 0.4064)
			(stroke
				(width 0.1524)
				(type default)
			)
			(layer "B.SilkS")
		)
		(fp_line
			(start 0.67945 -0.305054)
			(end 0.12065 -0.305054)
			(stroke
				(width 0.1)
				(type default)
			)
			(layer "B.Fab")
		)
		(fp_line
			(start 0.12065 -0.305054)
			(end 0.12065 -0.2794)
			(stroke
				(width 0.1)
				(type default)
			)
			(layer "B.Fab")
		)
		(fp_line
			(start -0.12065 -0.3048)
			(end -0.67945 -0.3048)
			(stroke
				(width 0.1)
				(type default)
			)
			(layer "B.Fab")
		)
		(fp_line
			(start -0.67945 -0.3048)
			(end -0.67945 0.3048)
			(stroke
				(width 0.1)
				(type default)
			)
			(layer "B.Fab")
		)
		(fp_line
			(start 0.12065 -0.2794)
			(end -0.12065 -0.2794)
			(stroke
				(width 0.1)
				(type default)
			)
			(layer "B.Fab")
		)
		(fp_line
			(start -0.12065 -0.2794)
			(end -0.12065 -0.3048)
			(stroke
				(width 0.1)
				(type default)
			)
			(layer "B.Fab")
		)
		(fp_line
			(start 0.12065 0.2794)
			(end 0.12065 0.3048)
			(stroke
				(width 0.1)
				(type default)
			)
			(layer "B.Fab")
		)
		(fp_line
			(start -0.120396 0.2794)
			(end 0.12065 0.2794)
			(stroke
				(width 0.1)
				(type default)
			)
			(layer "B.Fab")
		)
		(fp_line
			(start 0.67945 0.3048)
			(end 0.67945 -0.305054)
			(stroke
				(width 0.1)
				(type default)
			)
			(layer "B.Fab")
		)
		(fp_line
			(start 0.12065 0.3048)
			(end 0.67945 0.3048)
			(stroke
				(width 0.1)
				(type default)
			)
			(layer "B.Fab")
		)
		(fp_line
			(start -0.120396 0.3048)
			(end -0.120396 0.2794)
			(stroke
				(width 0.1)
				(type default)
			)
			(layer "B.Fab")
		)
		(fp_line
			(start -0.67945 0.3048)
			(end -0.120396 0.3048)
			(stroke
				(width 0.1)
				(type default)
			)
			(layer "B.Fab")
		)
		(pad "1" smd circle
			(at 0.40005 0 270)
			(size 0 0)
			(layers "B.Cu" "B.Mask" "B.Paste")
			(net "SPI_BMC_MISO_IO1_R")
		)
		(pad "2" smd circle
			(at -0.40005 0 270)
			(size 0 0)
			(layers "B.Cu" "B.Mask" "B.Paste")
			(net "QSPI_2_PLD_IO1")
		)
	)
	(footprint ""
		(layer "B.Cu")
		(at 14.7828 -94.6404 180)
		(property "Reference" "R51"
			(at 0 0 0)
			(layer "B.SilkS")
			(hide yes)
			(effects
				(font
					(size 1.27 1.27)
				)
				(justify mirror)
			)
		)
		(property "Value" ""
			(at 0 0 0)
			(layer "B.Fab")
			(effects
				(font
					(size 1.27 1.27)
				)
				(justify mirror)
			)
		)
		(duplicate_pad_numbers_are_jumpers no)
		(fp_line
			(start 0.7874 0.4064)
			(end 0.7874 -0.4064)
			(stroke
				(width 0.1524)
				(type default)
			)
			(layer "B.SilkS")
		)
		(fp_line
			(start 0.7874 -0.4064)
			(end -0.7874 -0.4064)
			(stroke
				(width 0.1524)
				(type default)
			)
			(layer "B.SilkS")
		)
		(fp_line
			(start -0.7874 0.4064)
			(end 0.7874 0.4064)
			(stroke
				(width 0.1524)
				(type default)
			)
			(layer "B.SilkS")
		)
		(fp_line
			(start -0.7874 -0.4064)
			(end -0.7874 0.4064)
			(stroke
				(width 0.1524)
				(type default)
			)
			(layer "B.SilkS")
		)
		(fp_line
			(start 0.67945 0.3048)
			(end 0.67945 -0.305054)
			(stroke
				(width 0.1)
				(type default)
			)
			(layer "B.Fab")
		)
		(fp_line
			(start 0.67945 -0.305054)
			(end 0.12065 -0.305054)
			(stroke
				(width 0.1)
				(type default)
			)
			(layer "B.Fab")
		)
		(fp_line
			(start 0.12065 0.3048)
			(end 0.67945 0.3048)
			(stroke
				(width 0.1)
				(type default)
			)
			(layer "B.Fab")
		)
		(fp_line
			(start 0.12065 0.2794)
			(end 0.12065 0.3048)
			(stroke
				(width 0.1)
				(type default)
			)
			(layer "B.Fab")
		)
		(fp_line
			(start 0.12065 -0.2794)
			(end -0.12065 -0.2794)
			(stroke
				(width 0.1)
				(type default)
			)
			(layer "B.Fab")
		)
		(fp_line
			(start 0.12065 -0.305054)
			(end 0.12065 -0.2794)
			(stroke
				(width 0.1)
				(type default)
			)
			(layer "B.Fab")
		)
		(fp_line
			(start -0.120396 0.3048)
			(end -0.120396 0.2794)
			(stroke
				(width 0.1)
				(type default)
			)
			(layer "B.Fab")
		)
		(fp_line
			(start -0.120396 0.2794)
			(end 0.12065 0.2794)
			(stroke
				(width 0.1)
				(type default)
			)
			(layer "B.Fab")
		)
		(fp_line
			(start -0.12065 -0.2794)
			(end -0.12065 -0.3048)
			(stroke
				(width 0.1)
				(type default)
			)
			(layer "B.Fab")
		)
		(fp_line
			(start -0.12065 -0.3048)
			(end -0.67945 -0.3048)
			(stroke
				(width 0.1)
				(type default)
			)
			(layer "B.Fab")
		)
		(fp_line
			(start -0.67945 0.3048)
			(end -0.120396 0.3048)
			(stroke
				(width 0.1)
				(type default)
			)
			(layer "B.Fab")
		)
		(fp_line
			(start -0.67945 -0.3048)
			(end -0.67945 0.3048)
			(stroke
				(width 0.1)
				(type default)
			)
			(layer "B.Fab")
		)
		(pad "1" smd circle
			(at 0.40005 0)
			(size 0 0)
			(layers "B.Cu" "B.Mask" "B.Paste")
			(net "H_CPU0_PROCHOT_LVC1_N")
		)
		(pad "2" smd circle
			(at -0.40005 0)
			(size 0 0)
			(layers "B.Cu" "B.Mask" "B.Paste")
			(net "H_CPU0_PROCHOT_LVC1_R_N")
		)
	)
)
